# T6G (Grand Teton) — schematic netlist excerpt (pin names and nets, part order shuffled) for the footprints in the layout excerpt that follows; sources: Cadence DE-HDL packaged netlist, KiCad conversion of 04192023_DAF0TMB3IC0_F0TG_MB_C_brd_V02_OCP.brd

PC343  Q_CAPP  470UF 2.5V 20% SPCAP  pkg SMLF  page 215 : A = PVDDCR_SOC_P1 ; B = GND
C2153  Q_CAP  22UF 4V 20% X6S  pkg C0402  page 68 : A = PVDD11_S3_P0 ; B = GND

(kicad_pcb
	(version 20260206)
	(generator "pcbnew")
	(generator_version "10.0")
	(general
		(thickness 1.6)
		(legacy_teardrops no)
	)
	(paper "A4")
	(title_block
		(title "04192023_DAF0TMB3IC0_F0TG_MB_C_brd_V02_OCP.brd")
		(comment 1 "Grand Teton / footprints 5531-5532 of 8354")
	)
	(layers
		(0 "F.Cu" signal "TOP")
		(4 "In1.Cu" signal "GND")
		(6 "In2.Cu" signal "IN1")
		(8 "In3.Cu" signal "GND1")
		(10 "In4.Cu" signal "IN2")
		(12 "In5.Cu" signal "GND2")
		(14 "In6.Cu" signal "IN3")
		(16 "In7.Cu" signal "GND3")
		(18 "In8.Cu" signal "VCC")
		(20 "In9.Cu" signal "VCC1")
		(22 "In10.Cu" signal "GND4")
		(24 "In11.Cu" signal "IN4")
		(26 "In12.Cu" signal "GND5")
		(28 "In13.Cu" signal "IN5")
		(30 "In14.Cu" signal "GND6")
		(32 "In15.Cu" signal "IN6")
		(34 "In16.Cu" signal "GND7")
		(2 "B.Cu" signal "BOTTOM")
		(9 "F.Adhes" user "F.Adhesive")
		(11 "B.Adhes" user "B.Adhesive")
		(13 "F.Paste" user "Package Geometry/Pastemask Top")
		(15 "B.Paste" user "Package Geometry/Pastemask Bottom")
		(5 "F.SilkS" user "Ref Des/Silkscreen Top")
		(7 "B.SilkS" user "Ref Des/Silkscreen Bottom")
		(1 "F.Mask" user "Board Geometry/Soldermask Top")
		(3 "B.Mask" user "Board Geometry/Soldermask Bottom")
		(17 "Dwgs.User" user "User.Drawings")
		(19 "Cmts.User" user "User.Comments")
		(21 "Eco1.User" user "User.Eco1")
		(23 "Eco2.User" user "User.Eco2")
		(25 "Edge.Cuts" user "Board Geometry/Outline")
		(27 "Margin" user)
		(31 "F.CrtYd" user "Package Geometry/Place Bound Top")
		(29 "B.CrtYd" user "Package Geometry/Place Bound Bottom")
		(35 "F.Fab" user "Ref Des/Assembly Top")
		(33 "B.Fab" user "Ref Des/Assembly Bottom")
	)
	(footprint ""
		(layer "B.Cu")
		(at 116.116354 -178.658012 90)
		(property "Reference" "PC343"
			(at 6.671056 -0.439166 270)
			(unlocked yes)
			(layer "B.SilkS")
			(effects
				(font
					(size 0.7874 0.5842)
					(thickness 0.1524)
				)
				(justify left mirror)
			)
		)
		(property "Value" ""
			(at 0 0 90)
			(layer "B.Fab")
			(effects
				(font
					(size 1.27 1.27)
				)
				(justify mirror)
			)
		)
		(duplicate_pad_numbers_are_jumpers no)
		(fp_line
			(start 4.533392 -2.249932)
			(end -4.533392 -2.249932)
			(stroke
				(width 0.1524)
				(type default)
			)
			(layer "B.SilkS")
		)
		(fp_line
			(start -4.533392 -2.249932)
			(end -4.533392 2.249932)
			(stroke
				(width 0.1524)
				(type default)
			)
			(layer "B.SilkS")
		)
		(fp_line
			(start 4.533392 2.249932)
			(end 4.533392 -2.249932)
			(stroke
				(width 0.1524)
				(type default)
			)
			(layer "B.SilkS")
		)
		(fp_line
			(start -4.533392 2.249932)
			(end 4.533392 2.249932)
			(stroke
				(width 0.1524)
				(type default)
			)
			(layer "B.SilkS")
		)
		(fp_rect
			(start 4.533392 -2.326132)
			(end 5.39242 2.326132)
			(stroke
				(width 0)
				(type default)
			)
			(fill yes)
			(layer "B.SilkS")
		)
		(fp_line
			(start 3.750056 -2.249932)
			(end -3.750056 -2.249932)
			(stroke
				(width 0.1)
				(type default)
			)
			(layer "B.Fab")
		)
		(fp_line
			(start -3.750056 -2.249932)
			(end -3.750056 2.249932)
			(stroke
				(width 0.1)
				(type default)
			)
			(layer "B.Fab")
		)
		(fp_line
			(start 3.750056 2.249932)
			(end 3.750056 -2.249932)
			(stroke
				(width 0.1)
				(type default)
			)
			(layer "B.Fab")
		)
		(fp_line
			(start -3.750056 2.249932)
			(end 3.750056 2.249932)
			(stroke
				(width 0.1)
				(type default)
			)
			(layer "B.Fab")
		)
		(fp_text user "-"
			(at -4.8514 -0.14605 90)
			(unlocked yes)
			(layer "B.SilkS")
			(effects
				(font
					(size 1.905 1.4224)
					(thickness 0.1524)
				)
				(justify left mirror)
			)
		)
		(fp_text user "+"
			(at 6.322314 0.786384 0)
			(unlocked yes)
			(layer "B.SilkS")
			(effects
				(font
					(size 1.905 1.4224)
					(thickness 0.1524)
				)
				(justify left mirror)
			)
		)
		(fp_text user "-"
			(at -4.8514 -0.14605 90)
			(unlocked yes)
			(layer "B.Fab")
			(effects
				(font
					(size 1.905 1.4224)
					(thickness 0.1524)
				)
				(justify left mirror)
			)
		)
		(fp_text user "+"
			(at 6.322314 0.786384 0)
			(unlocked yes)
			(layer "B.Fab")
			(effects
				(font
					(size 1.905 1.4224)
					(thickness 0.1524)
				)
				(justify left mirror)
			)
		)
		(pad "1" smd rect
			(at 3.199892 0 270)
			(size 2.413 2.8194)
			(layers "B.Cu" "B.Mask" "B.Paste")
			(net "PVDDCR_SOC_P1")
		)
		(pad "2" smd rect
			(at -3.199892 0 270)
			(size 2.413 2.8194)
			(layers "B.Cu" "B.Mask" "B.Paste")
			(net "GND")
		)
	)
	(footprint ""
		(layer "B.Cu")
		(at 357.517192 -261.747762 90)
		(property "Reference" "C2153"
			(at 0 0 90)
			(layer "B.SilkS")
			(hide yes)
			(effects
				(font
					(size 1.27 1.27)
				)
				(justify mirror)
			)
		)
		(property "Value" ""
			(at 0 0 90)
			(layer "B.Fab")
			(effects
				(font
					(size 1.27 1.27)
				)
				(justify mirror)
			)
		)
		(duplicate_pad_numbers_are_jumpers no)
		(fp_line
			(start 0.7874 -0.4064)
			(end -0.7874 -0.4064)
			(stroke
				(width 0.1524)
				(type default)
			)
			(layer "B.SilkS")
		)
		(fp_line
			(start -0.7874 -0.4064)
			(end -0.7874 0.4064)
			(stroke
				(width 0.1524)
				(type default)
			)
			(layer "B.SilkS")
		)
		(fp_line
			(start 0.7874 0.4064)
			(end 0.7874 -0.4064)
			(stroke
				(width 0.1524)
				(type default)
			)
			(layer "B.SilkS")
		)
		(fp_line
			(start -0.7874 0.4064)
			(end 0.7874 0.4064)
			(stroke
				(width 0.1524)
				(type default)
			)
			(layer "B.SilkS")
		)
		(fp_line
			(start 0.67945 -0.305054)
			(end 0.12065 -0.305054)
			(stroke
				(width 0.1)
				(type default)
			)
			(layer "B.Fab")
		)
		(fp_line
			(start 0.12065 -0.305054)
			(end 0.12065 -0.2794)
			(stroke
				(width 0.1)
				(type default)
			)
			(layer "B.Fab")
		)
		(fp_line
			(start -0.12065 -0.3048)
			(end -0.67945 -0.3048)
			(stroke
				(width 0.1)
				(type default)
			)
			(layer "B.Fab")
		)
		(fp_line
			(start -0.67945 -0.3048)
			(end -0.67945 0.3048)
			(stroke
				(width 0.1)
				(type default)
			)
			(layer "B.Fab")
		)
		(fp_line
			(start 0.12065 -0.2794)
			(end -0.12065 -0.2794)
			(stroke
				(width 0.1)
				(type default)
			)
			(layer "B.Fab")
		)
		(fp_line
			(start -0.12065 -0.2794)
			(end -0.12065 -0.3048)
			(stroke
				(width 0.1)
				(type default)
			)
			(layer "B.Fab")
		)
		(fp_line
			(start 0.12065 0.2794)
			(end 0.12065 0.3048)
			(stroke
				(width 0.1)
				(type default)
			)
			(layer "B.Fab")
		)
		(fp_line
			(start -0.120396 0.2794)
			(end 0.12065 0.2794)
			(stroke
				(width 0.1)
				(type default)
			)
			(layer "B.Fab")
		)
		(fp_line
			(start 0.67945 0.3048)
			(end 0.67945 -0.305054)
			(stroke
				(width 0.1)
				(type default)
			)
			(layer "B.Fab")
		)
		(fp_line
			(start 0.12065 0.3048)
			(end 0.67945 0.3048)
			(stroke
				(width 0.1)
				(type default)
			)
			(layer "B.Fab")
		)
		(fp_line
			(start -0.120396 0.3048)
			(end -0.120396 0.2794)
			(stroke
				(width 0.1)
				(type default)
			)
			(layer "B.Fab")
		)
		(fp_line
			(start -0.67945 0.3048)
			(end -0.120396 0.3048)
			(stroke
				(width 0.1)
				(type default)
			)
			(layer "B.Fab")
		)
		(pad "1" smd circle
			(at 0.40005 0 270)
			(size 0 0)
			(layers "B.Cu" "B.Mask" "B.Paste")
			(net "PVDD11_S3_P0")
		)
		(pad "2" smd circle
			(at -0.40005 0 270)
			(size 0 0)
			(layers "B.Cu" "B.Mask" "B.Paste")
			(net "GND")
		)
	)
)
